(kicad_pcb
	(version 20260206)
	(generator "pcbnew")
	(generator_version "10.0")
	(general
		(thickness 1.6)
		(legacy_teardrops no)
	)
	(paper "A4")
	(title_block
		(title "panther-plus-userver — 13130-1b_20150205.brd")
		(comment 1 "Honey Badger (Wiwynn) / footprints 766-773 of 1509")
	)
	(layers
		(0 "F.Cu" signal "TOP")
		(4 "In1.Cu" signal "L2")
		(6 "In2.Cu" signal "L3")
		(8 "In3.Cu" signal "L4")
		(10 "In4.Cu" signal "L5")
		(12 "In5.Cu" signal "L6")
		(14 "In6.Cu" signal "L7")
		(16 "In7.Cu" signal "L8")
		(18 "In8.Cu" signal "L9")
		(20 "In9.Cu" signal "L10")
		(22 "In10.Cu" signal "L11")
		(2 "B.Cu" signal "BOTTOM")
		(9 "F.Adhes" user "F.Adhesive")
		(11 "B.Adhes" user "B.Adhesive")
		(13 "F.Paste" user "Package Geometry/Pastemask Top")
		(15 "B.Paste" user "Package Geometry/Pastemask Bottom")
		(5 "F.SilkS" user "Ref Des/Silkscreen Top")
		(7 "B.SilkS" user "Ref Des/Silkscreen Bottom")
		(1 "F.Mask" user "Board Geometry/Soldermask Top")
		(3 "B.Mask" user "Board Geometry/Soldermask Bottom")
		(17 "Dwgs.User" user "User.Drawings")
		(19 "Cmts.User" user "User.Comments")
		(21 "Eco1.User" user "User.Eco1")
		(23 "Eco2.User" user "User.Eco2")
		(25 "Edge.Cuts" user "Board Geometry/Outline")
		(27 "Margin" user)
		(31 "F.CrtYd" user "Package Geometry/Place Bound Top")
		(29 "B.CrtYd" user "Package Geometry/Place Bound Bottom")
		(35 "F.Fab" user "Ref Des/Assembly Top")
		(33 "B.Fab" user "Ref Des/Assembly Bottom")
	)
	(footprint ""
		(layer "F.Cu")
		(at 198.12 -7.112 90)
		(property "Reference" "R387"
			(at 0 0 90)
			(layer "F.SilkS")
			(hide yes)
			(effects
				(font
					(size 1.27 1.27)
				)
			)
		)
		(property "Value" "4K7R2F-GP"
			(at 0.064008 -3.993896 90)
			(unlocked yes)
			(layer "F.Fab")
			(hide yes)
			(effects
				(font
					(size 1.016 1.016)
					(thickness 0.1524)
				)
			)
		)
		(property "Device Type" "R402H16"
			(at 0.064008 -5.517896 90)
			(unlocked yes)
			(layer "F.Fab")
			(hide yes)
			(effects
				(font
					(size 1.016 1.016)
					(thickness 0.1524)
				)
			)
		)
		(duplicate_pad_numbers_are_jumpers no)
		(fp_rect
			(start -0.381 0.8382)
			(end 0.381 -0.8382)
			(stroke
				(width 0)
				(type default)
			)
			(fill no)
			(layer "F.CrtYd")
		)
		(fp_rect
			(start -0.381 0.8382)
			(end 0.381 -0.8382)
			(stroke
				(width 0)
				(type default)
			)
			(fill no)
			(layer "F.Fab")
		)
		(pad "1" smd custom
			(at 0 -0.4318 90)
			(size 0.127 0.127)
			(layers "F.Cu" "F.Mask" "F.Paste")
			(net "CHB_1_SA0")
			(options
				(clearance outline)
				(anchor circle)
			)
			(primitives
				(gr_poly
					(pts
						(arc
							(start -0.2032 -0.2794)
							(mid -0.239121 -0.264521)
							(end -0.254 -0.2286)
						)
						(arc
							(start -0.254 0.2286)
							(mid -0.239121 0.264521)
							(end -0.2032 0.2794)
						)
						(arc
							(start 0.2032 0.2794)
							(mid 0.239121 0.264521)
							(end 0.254 0.2286)
						)
						(arc
							(start 0.254 -0.2286)
							(mid 0.239121 -0.264521)
							(end 0.2032 -0.2794)
						)
					)
					(width 0)
					(fill yes)
				)
			)
		)
		(pad "2" smd custom
			(at 0 0.4318 90)
			(size 0.127 0.127)
			(layers "F.Cu" "F.Mask" "F.Paste")
			(net "GND")
			(options
				(clearance outline)
				(anchor circle)
			)
			(primitives
				(gr_poly
					(pts
						(arc
							(start -0.2032 -0.2794)
							(mid -0.239121 -0.264521)
							(end -0.254 -0.2286)
						)
						(arc
							(start -0.254 0.2286)
							(mid -0.239121 0.264521)
							(end -0.2032 0.2794)
						)
						(arc
							(start 0.2032 0.2794)
							(mid 0.239121 0.264521)
							(end 0.254 0.2286)
						)
						(arc
							(start 0.254 -0.2286)
							(mid 0.239121 -0.264521)
							(end 0.2032 -0.2794)
						)
					)
					(width 0)
					(fill yes)
				)
			)
		)
	)
	(footprint ""
		(layer "F.Cu")
		(at 175.641 -57.15 180)
		(property "Reference" "R181"
			(at 0 0 180)
			(layer "F.SilkS")
			(hide yes)
			(effects
				(font
					(size 1.27 1.27)
				)
			)
		)
		(property "Value" "4K7R2F-GP"
			(at 0.064008 -3.993896 180)
			(unlocked yes)
			(layer "F.Fab")
			(hide yes)
			(effects
				(font
					(size 1.016 1.016)
					(thickness 0.1524)
				)
			)
		)
		(property "Device Type" "R402H16"
			(at 0.064008 -5.517896 180)
			(unlocked yes)
			(layer "F.Fab")
			(hide yes)
			(effects
				(font
					(size 1.016 1.016)
					(thickness 0.1524)
				)
			)
		)
		(duplicate_pad_numbers_are_jumpers no)
		(fp_rect
			(start -0.381 0.8382)
			(end 0.381 -0.8382)
			(stroke
				(width 0)
				(type default)
			)
			(fill no)
			(layer "F.CrtYd")
		)
		(fp_rect
			(start -0.381 0.8382)
			(end 0.381 -0.8382)
			(stroke
				(width 0)
				(type default)
			)
			(fill no)
			(layer "F.Fab")
		)
		(pad "1" smd custom
			(at 0 -0.4318 180)
			(size 0.127 0.127)
			(layers "F.Cu" "F.Mask" "F.Paste")
			(net "EEPROM_A1")
			(options
				(clearance outline)
				(anchor circle)
			)
			(primitives
				(gr_poly
					(pts
						(arc
							(start -0.2032 -0.2794)
							(mid -0.239121 -0.264521)
							(end -0.254 -0.2286)
						)
						(arc
							(start -0.254 0.2286)
							(mid -0.239121 0.264521)
							(end -0.2032 0.2794)
						)
						(arc
							(start 0.2032 0.2794)
							(mid 0.239121 0.264521)
							(end 0.254 0.2286)
						)
						(arc
							(start 0.254 -0.2286)
							(mid 0.239121 -0.264521)
							(end 0.2032 -0.2794)
						)
					)
					(width 0)
					(fill yes)
				)
			)
		)
		(pad "2" smd custom
			(at 0 0.4318 180)
			(size 0.127 0.127)
			(layers "F.Cu" "F.Mask" "F.Paste")
			(net "GND")
			(options
				(clearance outline)
				(anchor circle)
			)
			(primitives
				(gr_poly
					(pts
						(arc
							(start -0.2032 -0.2794)
							(mid -0.239121 -0.264521)
							(end -0.254 -0.2286)
						)
						(arc
							(start -0.254 0.2286)
							(mid -0.239121 0.264521)
							(end -0.2032 0.2794)
						)
						(arc
							(start 0.2032 0.2794)
							(mid 0.239121 0.264521)
							(end 0.254 0.2286)
						)
						(arc
							(start 0.254 -0.2286)
							(mid 0.239121 -0.264521)
							(end 0.2032 -0.2794)
						)
					)
					(width 0)
					(fill yes)
				)
			)
		)
	)
	(footprint ""
		(layer "F.Cu")
		(at 167.894 -31.877 -90)
		(property "Reference" "PC88"
			(at 0 0 270)
			(layer "F.SilkS")
			(hide yes)
			(effects
				(font
					(size 1.27 1.27)
				)
			)
		)
		(property "Value" "SC10U6D3V5KX-4GP"
			(at -0.0762 -6.1214 270)
			(unlocked yes)
			(layer "F.Fab")
			(hide yes)
			(effects
				(font
					(size 1.016 1.016)
					(thickness 0.1524)
				)
			)
		)
		(property "Device Type" "C805H58"
			(at -0.0762 -8.1534 270)
			(unlocked yes)
			(layer "F.Fab")
			(hide yes)
			(effects
				(font
					(size 1.016 1.016)
					(thickness 0.1524)
				)
			)
		)
		(duplicate_pad_numbers_are_jumpers no)
		(fp_line
			(start 0.6096 0)
			(end -0.6096 0)
			(stroke
				(width 0.3048)
				(type default)
			)
			(layer "F.SilkS")
		)
		(fp_poly
			(pts
				(xy -0.9017 1.4351) (xy 0.9017 1.4351) (xy 0.9017 -1.4351) (xy -0.9017 -1.4351)
			)
			(stroke
				(width 0)
				(type default)
			)
			(fill no)
			(layer "F.CrtYd")
		)
		(fp_poly
			(pts
				(xy 0.9017 1.4351) (xy 0.9017 -1.4351) (xy -0.9017 -1.4351) (xy -0.9017 1.4351)
			)
			(stroke
				(width 0)
				(type default)
			)
			(fill no)
			(layer "F.Fab")
		)
		(pad "1" smd rect
			(at 0 -0.8382 270)
			(size 1.5494 0.9398)
			(layers "F.Cu" "F.Mask" "F.Paste")
			(net "P1V8_STBY_LDO_IN1")
		)
		(pad "2" smd rect
			(at 0 0.8382 270)
			(size 1.5494 0.9398)
			(layers "F.Cu" "F.Mask" "F.Paste")
			(net "GND")
		)
	)
	(footprint ""
		(layer "F.Cu")
		(at 68.58 -21.082 180)
		(property "Reference" "R411"
			(at 0 0 180)
			(layer "F.SilkS")
			(hide yes)
			(effects
				(font
					(size 1.27 1.27)
				)
			)
		)
		(property "Value" "0R2J-2-GP"
			(at 1.7907 -1.1176 180)
			(unlocked yes)
			(layer "F.Fab")
			(hide yes)
			(effects
				(font
					(size 1.016 1.016)
					(thickness 0.1524)
				)
			)
		)
		(property "Device Type" "R402H16"
			(at 1.7907 -2.6416 180)
			(unlocked yes)
			(layer "F.Fab")
			(hide yes)
			(effects
				(font
					(size 1.016 1.016)
					(thickness 0.1524)
				)
			)
		)
		(duplicate_pad_numbers_are_jumpers no)
		(fp_rect
			(start -0.381 0.8382)
			(end 0.381 -0.8382)
			(stroke
				(width 0)
				(type default)
			)
			(fill no)
			(layer "F.CrtYd")
		)
		(fp_rect
			(start -0.381 0.8382)
			(end 0.381 -0.8382)
			(stroke
				(width 0)
				(type default)
			)
			(fill no)
			(layer "F.Fab")
		)
		(pad "1" smd custom
			(at 0 -0.4318 180)
			(size 0.127 0.127)
			(layers "F.Cu" "F.Mask" "F.Paste")
			(net "MSATA_PRESENT#")
			(options
				(clearance outline)
				(anchor circle)
			)
			(primitives
				(gr_poly
					(pts
						(arc
							(start -0.2032 -0.2794)
							(mid -0.239121 -0.264521)
							(end -0.254 -0.2286)
						)
						(arc
							(start -0.254 0.2286)
							(mid -0.239121 0.264521)
							(end -0.2032 0.2794)
						)
						(arc
							(start 0.2032 0.2794)
							(mid 0.239121 0.264521)
							(end 0.254 0.2286)
						)
						(arc
							(start 0.254 -0.2286)
							(mid 0.239121 -0.264521)
							(end 0.2032 -0.2794)
						)
					)
					(width 0)
					(fill yes)
				)
			)
		)
		(pad "2" smd custom
			(at 0 0.4318 180)
			(size 0.127 0.127)
			(layers "F.Cu" "F.Mask" "F.Paste")
			(net "MSATA_PRESENT_R#")
			(options
				(clearance outline)
				(anchor circle)
			)
			(primitives
				(gr_poly
					(pts
						(arc
							(start -0.2032 -0.2794)
							(mid -0.239121 -0.264521)
							(end -0.254 -0.2286)
						)
						(arc
							(start -0.254 0.2286)
							(mid -0.239121 0.264521)
							(end -0.2032 0.2794)
						)
						(arc
							(start 0.2032 0.2794)
							(mid 0.239121 0.264521)
							(end 0.254 0.2286)
						)
						(arc
							(start 0.254 -0.2286)
							(mid 0.239121 -0.264521)
							(end 0.2032 -0.2794)
						)
					)
					(width 0)
					(fill yes)
				)
			)
		)
	)
	(footprint ""
		(layer "F.Cu")
		(at 73.66 -37.465 90)
		(property "Reference" "R415"
			(at 0 0 90)
			(layer "F.SilkS")
			(hide yes)
			(effects
				(font
					(size 1.27 1.27)
				)
			)
		)
		(property "Value" "4K7R2F-GP"
			(at 1.7907 -1.1176 90)
			(unlocked yes)
			(layer "F.Fab")
			(hide yes)
			(effects
				(font
					(size 1.016 1.016)
					(thickness 0.1524)
				)
			)
		)
		(property "Device Type" "R402H16"
			(at 1.7907 -2.6416 90)
			(unlocked yes)
			(layer "F.Fab")
			(hide yes)
			(effects
				(font
					(size 1.016 1.016)
					(thickness 0.1524)
				)
			)
		)
		(duplicate_pad_numbers_are_jumpers no)
		(fp_rect
			(start -0.381 0.8382)
			(end 0.381 -0.8382)
			(stroke
				(width 0)
				(type default)
			)
			(fill no)
			(layer "F.CrtYd")
		)
		(fp_rect
			(start -0.381 0.8382)
			(end 0.381 -0.8382)
			(stroke
				(width 0)
				(type default)
			)
			(fill no)
			(layer "F.Fab")
		)
		(pad "1" smd custom
			(at 0 -0.4318 90)
			(size 0.127 0.127)
			(layers "F.Cu" "F.Mask" "F.Paste")
			(net "P3V3_CPU")
			(options
				(clearance outline)
				(anchor circle)
			)
			(primitives
				(gr_poly
					(pts
						(arc
							(start -0.2032 -0.2794)
							(mid -0.239121 -0.264521)
							(end -0.254 -0.2286)
						)
						(arc
							(start -0.254 0.2286)
							(mid -0.239121 0.264521)
							(end -0.2032 0.2794)
						)
						(arc
							(start 0.2032 0.2794)
							(mid 0.239121 0.264521)
							(end 0.254 0.2286)
						)
						(arc
							(start 0.254 -0.2286)
							(mid 0.239121 -0.264521)
							(end 0.2032 -0.2794)
						)
					)
					(width 0)
					(fill yes)
				)
			)
		)
		(pad "2" smd custom
			(at 0 0.4318 90)
			(size 0.127 0.127)
			(layers "F.Cu" "F.Mask" "F.Paste")
			(net "USB_OC#")
			(options
				(clearance outline)
				(anchor circle)
			)
			(primitives
				(gr_poly
					(pts
						(arc
							(start -0.2032 -0.2794)
							(mid -0.239121 -0.264521)
							(end -0.254 -0.2286)
						)
						(arc
							(start -0.254 0.2286)
							(mid -0.239121 0.264521)
							(end -0.2032 0.2794)
						)
						(arc
							(start 0.2032 0.2794)
							(mid 0.239121 0.264521)
							(end 0.254 0.2286)
						)
						(arc
							(start 0.254 -0.2286)
							(mid 0.239121 -0.264521)
							(end 0.2032 -0.2794)
						)
					)
					(width 0)
					(fill yes)
				)
			)
		)
	)
	(footprint ""
		(layer "F.Cu")
		(at 53.2892 -51.308 180)
		(property "Reference" "PC110"
			(at 0 0 180)
			(layer "F.SilkS")
			(hide yes)
			(effects
				(font
					(size 1.27 1.27)
				)
			)
		)
		(property "Value" "SC1U16V3KX-5GP"
			(at -0.0254 -2.0193 180)
			(unlocked yes)
			(layer "F.Fab")
			(hide yes)
			(effects
				(font
					(size 1.016 1.016)
					(thickness 0.1524)
				)
			)
		)
		(property "Device Type" "C603H36"
			(at -0.0254 -3.5433 180)
			(unlocked yes)
			(layer "F.Fab")
			(hide yes)
			(effects
				(font
					(size 1.016 1.016)
					(thickness 0.1524)
				)
			)
		)
		(duplicate_pad_numbers_are_jumpers no)
		(fp_line
			(start -0.4064 0)
			(end 0.4064 0)
			(stroke
				(width 0.2286)
				(type default)
			)
			(layer "F.SilkS")
		)
		(fp_rect
			(start -0.635 1.1811)
			(end 0.635 -1.1811)
			(stroke
				(width 0)
				(type default)
			)
			(fill no)
			(layer "F.CrtYd")
		)
		(fp_rect
			(start -0.635 1.1811)
			(end 0.635 -1.1811)
			(stroke
				(width 0)
				(type default)
			)
			(fill no)
			(layer "F.Fab")
		)
		(pad "1" smd custom
			(at 0 -0.6604 180)
			(size 0.19685 0.19685)
			(layers "F.Cu" "F.Mask" "F.Paste")
			(net "VR_AVIN_P1V0_STBY")
			(options
				(clearance outline)
				(anchor circle)
			)
			(primitives
				(gr_poly
					(pts
						(arc
							(start 0.508 -0.2921)
							(mid 0.478242 -0.363942)
							(end 0.4064 -0.3937)
						)
						(arc
							(start -0.4064 -0.3937)
							(mid -0.478242 -0.363942)
							(end -0.508 -0.2921)
						)
						(arc
							(start -0.508 0.2921)
							(mid -0.478242 0.363942)
							(end -0.4064 0.3937)
						)
						(arc
							(start 0.4064 0.3937)
							(mid 0.478242 0.363942)
							(end 0.508 0.2921)
						)
					)
					(width 0)
					(fill yes)
				)
			)
		)
		(pad "2" smd custom
			(at 0 0.6604 180)
			(size 0.19685 0.19685)
			(layers "F.Cu" "F.Mask" "F.Paste")
			(net "AGND_P1V0_STBY")
			(options
				(clearance outline)
				(anchor circle)
			)
			(primitives
				(gr_poly
					(pts
						(arc
							(start 0.508 -0.2921)
							(mid 0.478242 -0.363942)
							(end 0.4064 -0.3937)
						)
						(arc
							(start -0.4064 -0.3937)
							(mid -0.478242 -0.363942)
							(end -0.508 -0.2921)
						)
						(arc
							(start -0.508 0.2921)
							(mid -0.478242 0.363942)
							(end -0.4064 0.3937)
						)
						(arc
							(start 0.4064 0.3937)
							(mid 0.478242 0.363942)
							(end 0.508 0.2921)
						)
					)
					(width 0)
					(fill yes)
				)
			)
		)
	)
	(footprint ""
		(layer "F.Cu")
		(at 118.849902 -11.500104)
		(property "Reference" "CN2"
			(at 0 0 0)
			(layer "F.SilkS")
			(hide yes)
			(effects
				(font
					(size 1.27 1.27)
				)
			)
		)
		(property "Value" "PIN-CON2-6-GP-U"
			(at -4.9657 1.2954 0)
			(unlocked yes)
			(layer "F.Fab")
			(hide yes)
			(effects
				(font
					(size 1.016 1.016)
					(thickness 0.1524)
				)
			)
		)
		(property "Device Type" "21U-91-03TB22-U"
			(at -4.9657 -0.2286 0)
			(unlocked yes)
			(layer "F.Fab")
			(hide yes)
			(effects
				(font
					(size 1.016 1.016)
					(thickness 0.1524)
				)
			)
		)
		(duplicate_pad_numbers_are_jumpers no)
		(fp_line
			(start -3.937 -1.4986)
			(end 3.937 -1.4986)
			(stroke
				(width 0.1524)
				(type default)
			)
			(layer "F.SilkS")
		)
		(fp_line
			(start -3.937 1.4986)
			(end -3.937 -1.4986)
			(stroke
				(width 0.1524)
				(type default)
			)
			(layer "F.SilkS")
		)
		(fp_line
			(start 3.937 -1.4986)
			(end 3.937 1.4986)
			(stroke
				(width 0.1524)
				(type default)
			)
			(layer "F.SilkS")
		)
		(fp_line
			(start 3.937 1.4986)
			(end -3.937 1.4986)
			(stroke
				(width 0.1524)
				(type default)
			)
			(layer "F.SilkS")
		)
		(fp_circle
			(center -2.54 0)
			(end -1.4732 0)
			(stroke
				(width 0.3048)
				(type default)
			)
			(fill no)
			(layer "F.SilkS")
		)
		(fp_circle
			(center 2.54 0)
			(end 3.6068 0)
			(stroke
				(width 0.3048)
				(type default)
			)
			(fill no)
			(layer "F.SilkS")
		)
		(fp_rect
			(start -3.683 1.2446)
			(end 3.683 -1.2446)
			(stroke
				(width 0)
				(type default)
			)
			(fill no)
			(layer "F.CrtYd")
		)
		(fp_poly
			(pts
				(xy -4.191 1.7526) (xy -4.191 -1.7526) (xy 4.191 -1.7526) (xy 4.191 -0.00635) (xy 3.683 -0.00635)
				(xy 3.683 -1.2446) (xy -3.683 -1.2446) (xy -3.683 1.2446) (xy 3.683 1.2446) (xy 3.683 0.00635) (xy 4.191 0.00635)
				(xy 4.191 1.7526)
			)
			(stroke
				(width 0)
				(type default)
			)
			(fill no)
			(layer "F.CrtYd")
		)
		(fp_rect
			(start -4.191 1.7526)
			(end 4.191 -1.7526)
			(stroke
				(width 0)
				(type default)
			)
			(fill no)
			(layer "F.Fab")
		)
		(pad "1" thru_hole circle
			(at -2.54 0)
			(size 1.4224 1.4224)
			(drill 1.016)
			(layers "*.Cu" "*.Mask")
			(remove_unused_layers no)
			(net "DYMMY_NET2")
			(clearance 0.1524)
			(thermal_gap 0.1524)
		)
		(pad "2" thru_hole circle
			(at 2.54 0)
			(size 1.4224 1.4224)
			(drill 1.016)
			(layers "*.Cu" "*.Mask")
			(remove_unused_layers no)
			(net "DYMMY_NET2")
			(clearance 0.1524)
			(thermal_gap 0.1524)
		)
	)
	(footprint ""
		(layer "F.Cu")
		(at 74.168 -44.069 90)
		(property "Reference" "R416"
			(at 0 0 90)
			(layer "F.SilkS")
			(hide yes)
			(effects
				(font
					(size 1.27 1.27)
				)
			)
		)
		(property "Value" "10KR2F-2-GP"
			(at 1.7907 -1.1176 90)
			(unlocked yes)
			(layer "F.Fab")
			(hide yes)
			(effects
				(font
					(size 1.016 1.016)
					(thickness 0.1524)
				)
			)
		)
		(property "Device Type" "R402H16"
			(at 1.7907 -2.6416 90)
			(unlocked yes)
			(layer "F.Fab")
			(hide yes)
			(effects
				(font
					(size 1.016 1.016)
					(thickness 0.1524)
				)
			)
		)
		(duplicate_pad_numbers_are_jumpers no)
		(fp_rect
			(start -0.381 0.8382)
			(end 0.381 -0.8382)
			(stroke
				(width 0)
				(type default)
			)
			(fill no)
			(layer "F.CrtYd")
		)
		(fp_rect
			(start -0.381 0.8382)
			(end 0.381 -0.8382)
			(stroke
				(width 0)
				(type default)
			)
			(fill no)
			(layer "F.Fab")
		)
		(pad "1" smd custom
			(at 0 -0.4318 90)
			(size 0.127 0.127)
			(layers "F.Cu" "F.Mask" "F.Paste")
			(net "P3V3")
			(options
				(clearance outline)
				(anchor circle)
			)
			(primitives
				(gr_poly
					(pts
						(arc
							(start -0.2032 -0.2794)
							(mid -0.239121 -0.264521)
							(end -0.254 -0.2286)
						)
						(arc
							(start -0.254 0.2286)
							(mid -0.239121 0.264521)
							(end -0.2032 0.2794)
						)
						(arc
							(start 0.2032 0.2794)
							(mid 0.239121 0.264521)
							(end 0.254 0.2286)
						)
						(arc
							(start 0.254 -0.2286)
							(mid 0.239121 -0.264521)
							(end 0.2032 -0.2794)
						)
					)
					(width 0)
					(fill yes)
				)
			)
		)
		(pad "2" smd custom
			(at 0 0.4318 90)
			(size 0.127 0.127)
			(layers "F.Cu" "F.Mask" "F.Paste")
			(net "SMBUS_SW_R_EN")
			(options
				(clearance outline)
				(anchor circle)
			)
			(primitives
				(gr_poly
					(pts
						(arc
							(start -0.2032 -0.2794)
							(mid -0.239121 -0.264521)
							(end -0.254 -0.2286)
						)
						(arc
							(start -0.254 0.2286)
							(mid -0.239121 0.264521)
							(end -0.2032 0.2794)
						)
						(arc
							(start 0.2032 0.2794)
							(mid 0.239121 0.264521)
							(end 0.254 0.2286)
						)
						(arc
							(start 0.254 -0.2286)
							(mid 0.239121 -0.264521)
							(end 0.2032 -0.2794)
						)
					)
					(width 0)
					(fill yes)
				)
			)
		)
	)
)
